# S9S_MB_2U (Grand Teton) — schematic netlist excerpt (pin names and nets, part order shuffled) for the footprints in the layout excerpt that follows; sources: Cadence DE-HDL packaged netlist, KiCad conversion of 03242023_DA0F0TMBIJ0_F0T_Motherboard_J_brd_V01_OCP.brd

C927  Q_CAP_DIFFBUS  DIFF BUS_0.22UF 6.3V 20% X6S  pkg C0201  page 173 : \1\ = P5E_CPU0_PE0_TX_C_DP<3> ; \2\ = P5E_CPU0_PE0_TX_DP<3>
R3308  Q_RES  0 5% CHIP  pkg 0402LF  page 165 : A = OCP_V3_2_PRSNT_ALL_R_N ; B = OCP_V3_2_PRSNT_ALL_R1_N
C1027  Q_CAP  22UF 4V 20% X6S  pkg C0402  page 74 : A = PVCCIN_CPU0 ; B = GND

(kicad_pcb
	(version 20260206)
	(generator "pcbnew")
	(generator_version "10.0")
	(general
		(thickness 1.6)
		(legacy_teardrops no)
	)
	(paper "A4")
	(title_block
		(title "03242023_DA0F0TMBIJ0_F0T_Motherboard_J_brd_V01_OCP.brd")
		(comment 1 "Grand Teton / footprints 3068-3070 of 6105")
	)
	(layers
		(0 "F.Cu" signal "TOP")
		(4 "In1.Cu" signal "GND")
		(6 "In2.Cu" signal "IN1")
		(8 "In3.Cu" signal "GND1")
		(10 "In4.Cu" signal "IN2")
		(12 "In5.Cu" signal "GND2")
		(14 "In6.Cu" signal "IN3")
		(16 "In7.Cu" signal "GND3")
		(18 "In8.Cu" signal "VCC")
		(20 "In9.Cu" signal "VCC1")
		(22 "In10.Cu" signal "GND4")
		(24 "In11.Cu" signal "IN4")
		(26 "In12.Cu" signal "GND5")
		(28 "In13.Cu" signal "IN5")
		(30 "In14.Cu" signal "GND6")
		(32 "In15.Cu" signal "IN6")
		(34 "In16.Cu" signal "GND7")
		(2 "B.Cu" signal "BOTTOM")
		(9 "F.Adhes" user "F.Adhesive")
		(11 "B.Adhes" user "B.Adhesive")
		(13 "F.Paste" user "Package Geometry/Pastemask Top")
		(15 "B.Paste" user "Package Geometry/Pastemask Bottom")
		(5 "F.SilkS" user "Ref Des/Silkscreen Top")
		(7 "B.SilkS" user "Ref Des/Silkscreen Bottom")
		(1 "F.Mask" user "Board Geometry/Soldermask Top")
		(3 "B.Mask" user "Board Geometry/Soldermask Bottom")
		(17 "Dwgs.User" user "User.Drawings")
		(19 "Cmts.User" user "User.Comments")
		(21 "Eco1.User" user "User.Eco1")
		(23 "Eco2.User" user "User.Eco2")
		(25 "Edge.Cuts" user "Board Geometry/Outline")
		(27 "Margin" user)
		(31 "F.CrtYd" user "Package Geometry/Place Bound Top")
		(29 "B.CrtYd" user "Package Geometry/Place Bound Bottom")
		(35 "F.Fab" user "Ref Des/Assembly Top")
		(33 "B.Fab" user "Ref Des/Assembly Bottom")
	)
	(footprint ""
		(layer "F.Cu")
		(at 353.246944 -240.276888 90)
		(property "Reference" "C1027"
			(at 0 0 90)
			(layer "F.SilkS")
			(hide yes)
			(effects
				(font
					(size 1.27 1.27)
				)
			)
		)
		(property "Value" ""
			(at 0 0 90)
			(layer "F.Fab")
			(effects
				(font
					(size 1.27 1.27)
				)
			)
		)
		(duplicate_pad_numbers_are_jumpers no)
		(fp_line
			(start 0.7874 -0.4064)
			(end 0.7874 0.4064)
			(stroke
				(width 0.1524)
				(type default)
			)
			(layer "F.SilkS")
		)
		(fp_line
			(start -0.7874 -0.4064)
			(end 0.7874 -0.4064)
			(stroke
				(width 0.1524)
				(type default)
			)
			(layer "F.SilkS")
		)
		(fp_line
			(start 0.7874 0.4064)
			(end -0.7874 0.4064)
			(stroke
				(width 0.1524)
				(type default)
			)
			(layer "F.SilkS")
		)
		(fp_line
			(start -0.7874 0.4064)
			(end -0.7874 -0.4064)
			(stroke
				(width 0.1524)
				(type default)
			)
			(layer "F.SilkS")
		)
		(fp_line
			(start -0.12065 -0.305054)
			(end -0.12065 -0.2794)
			(stroke
				(width 0.1)
				(type default)
			)
			(layer "F.Fab")
		)
		(fp_line
			(start -0.67945 -0.305054)
			(end -0.12065 -0.305054)
			(stroke
				(width 0.1)
				(type default)
			)
			(layer "F.Fab")
		)
		(fp_line
			(start 0.67945 -0.3048)
			(end 0.67945 0.3048)
			(stroke
				(width 0.1)
				(type default)
			)
			(layer "F.Fab")
		)
		(fp_line
			(start 0.12065 -0.3048)
			(end 0.67945 -0.3048)
			(stroke
				(width 0.1)
				(type default)
			)
			(layer "F.Fab")
		)
		(fp_line
			(start 0.12065 -0.2794)
			(end 0.12065 -0.3048)
			(stroke
				(width 0.1)
				(type default)
			)
			(layer "F.Fab")
		)
		(fp_line
			(start -0.12065 -0.2794)
			(end 0.12065 -0.2794)
			(stroke
				(width 0.1)
				(type default)
			)
			(layer "F.Fab")
		)
		(fp_line
			(start 0.120396 0.2794)
			(end -0.12065 0.2794)
			(stroke
				(width 0.1)
				(type default)
			)
			(layer "F.Fab")
		)
		(fp_line
			(start -0.12065 0.2794)
			(end -0.12065 0.3048)
			(stroke
				(width 0.1)
				(type default)
			)
			(layer "F.Fab")
		)
		(fp_line
			(start 0.67945 0.3048)
			(end 0.120396 0.3048)
			(stroke
				(width 0.1)
				(type default)
			)
			(layer "F.Fab")
		)
		(fp_line
			(start 0.120396 0.3048)
			(end 0.120396 0.2794)
			(stroke
				(width 0.1)
				(type default)
			)
			(layer "F.Fab")
		)
		(fp_line
			(start -0.12065 0.3048)
			(end -0.67945 0.3048)
			(stroke
				(width 0.1)
				(type default)
			)
			(layer "F.Fab")
		)
		(fp_line
			(start -0.67945 0.3048)
			(end -0.67945 -0.305054)
			(stroke
				(width 0.1)
				(type default)
			)
			(layer "F.Fab")
		)
		(pad "1" smd circle
			(at -0.40005 0 90)
			(size 0 0)
			(layers "F.Cu" "F.Mask" "F.Paste")
			(net "PVCCIN_CPU0")
		)
		(pad "2" smd circle
			(at 0.40005 0 90)
			(size 0 0)
			(layers "F.Cu" "F.Mask" "F.Paste")
			(net "GND")
		)
	)
	(footprint ""
		(layer "F.Cu")
		(at 140.70838 -39.085012 180)
		(property "Reference" "R3308"
			(at 0 0 180)
			(layer "F.SilkS")
			(hide yes)
			(effects
				(font
					(size 1.27 1.27)
				)
			)
		)
		(property "Value" ""
			(at 0 0 180)
			(layer "F.Fab")
			(effects
				(font
					(size 1.27 1.27)
				)
			)
		)
		(duplicate_pad_numbers_are_jumpers no)
		(fp_line
			(start 0.7874 0.4064)
			(end -0.7874 0.4064)
			(stroke
				(width 0.1524)
				(type default)
			)
			(layer "F.SilkS")
		)
		(fp_line
			(start 0.7874 -0.4064)
			(end 0.7874 0.4064)
			(stroke
				(width 0.1524)
				(type default)
			)
			(layer "F.SilkS")
		)
		(fp_line
			(start -0.7874 0.4064)
			(end -0.7874 -0.4064)
			(stroke
				(width 0.1524)
				(type default)
			)
			(layer "F.SilkS")
		)
		(fp_line
			(start -0.7874 -0.4064)
			(end 0.7874 -0.4064)
			(stroke
				(width 0.1524)
				(type default)
			)
			(layer "F.SilkS")
		)
		(fp_line
			(start 0.67945 0.3048)
			(end 0.120396 0.3048)
			(stroke
				(width 0.1)
				(type default)
			)
			(layer "F.Fab")
		)
		(fp_line
			(start 0.67945 -0.3048)
			(end 0.67945 0.3048)
			(stroke
				(width 0.1)
				(type default)
			)
			(layer "F.Fab")
		)
		(fp_line
			(start 0.12065 -0.2794)
			(end 0.12065 -0.3048)
			(stroke
				(width 0.1)
				(type default)
			)
			(layer "F.Fab")
		)
		(fp_line
			(start 0.12065 -0.3048)
			(end 0.67945 -0.3048)
			(stroke
				(width 0.1)
				(type default)
			)
			(layer "F.Fab")
		)
		(fp_line
			(start 0.120396 0.3048)
			(end 0.120396 0.2794)
			(stroke
				(width 0.1)
				(type default)
			)
			(layer "F.Fab")
		)
		(fp_line
			(start 0.120396 0.2794)
			(end -0.12065 0.2794)
			(stroke
				(width 0.1)
				(type default)
			)
			(layer "F.Fab")
		)
		(fp_line
			(start -0.12065 0.3048)
			(end -0.67945 0.3048)
			(stroke
				(width 0.1)
				(type default)
			)
			(layer "F.Fab")
		)
		(fp_line
			(start -0.12065 0.2794)
			(end -0.12065 0.3048)
			(stroke
				(width 0.1)
				(type default)
			)
			(layer "F.Fab")
		)
		(fp_line
			(start -0.12065 -0.2794)
			(end 0.12065 -0.2794)
			(stroke
				(width 0.1)
				(type default)
			)
			(layer "F.Fab")
		)
		(fp_line
			(start -0.12065 -0.305054)
			(end -0.12065 -0.2794)
			(stroke
				(width 0.1)
				(type default)
			)
			(layer "F.Fab")
		)
		(fp_line
			(start -0.67945 0.3048)
			(end -0.67945 -0.305054)
			(stroke
				(width 0.1)
				(type default)
			)
			(layer "F.Fab")
		)
		(fp_line
			(start -0.67945 -0.305054)
			(end -0.12065 -0.305054)
			(stroke
				(width 0.1)
				(type default)
			)
			(layer "F.Fab")
		)
		(pad "1" smd circle
			(at -0.40005 0 180)
			(size 0 0)
			(layers "F.Cu" "F.Mask" "F.Paste")
			(net "OCP_V3_2_PRSNT_ALL_R_N")
		)
		(pad "2" smd circle
			(at 0.40005 0 180)
			(size 0 0)
			(layers "F.Cu" "F.Mask" "F.Paste")
			(net "OCP_V3_2_PRSNT_ALL_R1_N")
		)
	)
	(footprint ""
		(layer "F.Cu")
		(at 342.974168 -408.517344 -90)
		(property "Reference" "C927"
			(at 0 0 270)
			(layer "F.SilkS")
			(hide yes)
			(effects
				(font
					(size 1.27 1.27)
				)
			)
		)
		(property "Value" ""
			(at 0 0 270)
			(layer "F.Fab")
			(effects
				(font
					(size 1.27 1.27)
				)
			)
		)
		(duplicate_pad_numbers_are_jumpers no)
		(fp_line
			(start -0.299974 0.150114)
			(end -0.299974 -0.150114)
			(stroke
				(width 0.1)
				(type default)
			)
			(layer "F.Fab")
		)
		(fp_line
			(start 0.299974 0.150114)
			(end -0.299974 0.150114)
			(stroke
				(width 0.1)
				(type default)
			)
			(layer "F.Fab")
		)
		(fp_line
			(start -0.299974 -0.150114)
			(end 0.299974 -0.150114)
			(stroke
				(width 0.1)
				(type default)
			)
			(layer "F.Fab")
		)
		(fp_line
			(start 0.299974 -0.150114)
			(end 0.299974 0.150114)
			(stroke
				(width 0.1)
				(type default)
			)
			(layer "F.Fab")
		)
		(pad "1" smd rect
			(at -0.2667 0 270)
			(size 0.3048 0.381)
			(layers "F.Cu" "F.Mask" "F.Paste")
			(net "P5E_CPU0_PE0_TX_C_DP<3>")
		)
		(pad "2" smd rect
			(at 0.2667 0 270)
			(size 0.3048 0.381)
			(layers "F.Cu" "F.Mask" "F.Paste")
			(net "P5E_CPU0_PE0_TX_DP<3>")
		)
	)
)
